FILE_TYPE = MACRO_DRAWING;
SET COLOR_WIRE YELLOW;
SET COLOR_PROP ORANGE;
SET COLOR_DOT WHITE;
SET COLOR_ARC YELLOW;
SET COLOR_BODY GREEN;
SET COLOR_NOTE PURPLE;
SET PROP_DISPLAY VALUE;
SET PAGE_NUMBER P255;
FORCEADD UNIVERSAL_POWER..1
(1350 3875);
FORCEPROP 3 LASTPIN (1350 3825) SIG_NAME P3V3_AUX\g
J 0
(1360 3835);
DISPLAY 0.659574 (1360 3835);
PAINT MONO (1360 3835);
DISPLAY INVISIBLE (1360 3835);
FORCEPROP 1 LAST HDL_POWER P3V3_AUX
J 1
(1350 3925);
DISPLAY 0.872340 (1350 3925);
PAINT GREEN (1350 3925);
FORCEPROP 2 LAST CDS_LIB pure_quanta_power
J 0
(1350 3875);
PAINT MONO (1350 3875);
DISPLAY INVISIBLE (1350 3875);
FORCEPROP 1 LAST PATH I11
J 0
(1400 3900);
DISPLAY 0.872340 (1400 3900);
PAINT AQUA (1400 3900);
DISPLAY INVISIBLE (1400 3900);
FORCEADD UNIVERSAL_GND..1
(1350 3325);
FORCEPROP 3 LASTPIN (1350 3375) SIG_NAME GND\g
J 0
(1360 3385);
DISPLAY 0.659574 (1360 3385);
PAINT MONO (1360 3385);
DISPLAY INVISIBLE (1360 3385);
FORCEPROP 2 LAST CDS_LIB pure_quanta_power
J 0
(1350 3325);
PAINT MONO (1350 3325);
DISPLAY INVISIBLE (1350 3325);
FORCEPROP 1 LAST HDL_POWER GND
J 1
(1375 3250);
DISPLAY 0.872340 (1375 3250);
PAINT GREEN (1375 3250);
DISPLAY INVISIBLE (1375 3250);
FORCEPROP 1 LAST PATH I12
J 0
(1425 3325);
DISPLAY 0.872340 (1425 3325);
PAINT AQUA (1425 3325);
DISPLAY INVISIBLE (1425 3325);
FORCEADD Q_CAP..1
(1350 3550);
FORCEPROP 1 LAST LOCATION C1963
J 0
(1400 3650);
DISPLAY 0.787234 (1400 3650);
FORCEPROP 2 LAST $SEC 1
J 0
(1400 3750);
DISPLAY 0.680851 (1400 3750);
PAINT MONO (1400 3750);
DISPLAY INVISIBLE (1400 3750);
FORCEPROP 2 LAST CDS_SEC 1
J 0
(1400 3750);
DISPLAY 1.021277 (1400 3750);
DISPLAY INVISIBLE (1400 3750);
FORCEPROP 1 LASTPIN (1350 3650) $PN 1
J 0
(1360 3630);
DISPLAY 0.787234 (1360 3630);
FORCEPROP 1 LASTPIN (1350 3450) $PN 2
J 0
(1360 3430);
DISPLAY 0.787234 (1360 3430);
FORCEPROP 1 LAST TOLERANCE 10%
J 0
(1400 3500);
DISPLAY 0.510638 (1400 3500);
FORCEPROP 1 LAST VOLTAGE 25V
J 0
(1400 3550);
DISPLAY 0.510638 (1400 3550);
FORCEPROP 1 LAST PACK_TYPE 0402
J 0
(1400 3350);
DISPLAY 0.510638 (1400 3350);
FORCEPROP 1 LAST VALUE 0.1UF
J 0
(1400 3600);
DISPLAY 0.510638 (1400 3600);
FORCEPROP 1 LAST MATERIAL X7R
J 0
(1400 3450);
DISPLAY 0.510638 (1400 3450);
FORCEPROP 2 LAST CDS_LIB pure_quanta
J 2
(1350 3550);
PAINT MONO (1350 3550);
DISPLAY INVISIBLE (1350 3550);
FORCEPROP 1 LAST PATH I13
J 0
(1400 3700);
DISPLAY 0.978723 (1400 3700);
PAINT WHITE (1400 3700);
DISPLAY INVISIBLE (1400 3700);
FORCEPROP 1 LAST PART_NUMBER CH4104K1B00
J 0
(1400 3400);
DISPLAY 0.510638 (1400 3400);
DISPLAY INVISIBLE (1400 3400);
FORCEADD 74LVC2G07DW7..1
(775 3750);
FORCEPROP 1 LAST LOCATION U255
J 0
(606 4131);
DISPLAY 0.723404 (606 4131);
PAINT GREEN (606 4131);
FORCEPROP 0 LAST $SEC 1
J 0
(625 4275);
DISPLAY 0.680851 (625 4275);
PAINT MONO (625 4275);
DISPLAY INVISIBLE (625 4275);
FORCEPROP 0 LAST CDS_SEC 1
J 0
(625 4275);
DISPLAY 1.021277 (625 4275);
DISPLAY INVISIBLE (625 4275);
FORCEPROP 0 LASTPIN (450 3800) $PN 1
J 2
(440 3810);
DISPLAY 0.680851 (440 3810);
PAINT MONO (440 3810);
FORCEPROP 0 LASTPIN (1100 3800) $PN 6
J 0
(1110 3810);
DISPLAY 0.680851 (1110 3810);
PAINT MONO (1110 3810);
FORCEPROP 0 LASTPIN (450 3700) $PN 3
J 2
(440 3710);
DISPLAY 0.680851 (440 3710);
PAINT MONO (440 3710);
FORCEPROP 0 LASTPIN (1100 3700) $PN 4
J 0
(1110 3710);
DISPLAY 0.680851 (1110 3710);
PAINT MONO (1110 3710);
FORCEPROP 0 LASTPIN (450 3750) $PN 2
J 2
(440 3760);
DISPLAY 0.680851 (440 3760);
PAINT MONO (440 3760);
FORCEPROP 0 LASTPIN (1100 3750) $PN 5
J 0
(1110 3760);
DISPLAY 0.680851 (1110 3760);
PAINT MONO (1110 3760);
FORCEPROP 2 LAST VALUE 74LVC2G07DW-7
J 0
(475 4050);
DISPLAY 1.021277 (475 4050);
FORCEPROP 2 LAST PART_TYPE SMLF
J 0
(625 4225);
DISPLAY 1.021277 (625 4225);
FORCEPROP 1 LAST MATERIAL IC
J 0
(606 3857);
DISPLAY 0.723404 (606 3857);
PAINT GREEN (606 3857);
FORCEPROP 2 LAST CDS_LIB pure_quanta
J 0
(775 3750);
DISPLAY INVISIBLE (775 3750);
FORCEPROP 1 LAST NEEDS_NO_SIZE TRUE
J 0
(775 3750);
DISPLAY 0.723404 (775 3750);
PAINT GREEN (775 3750);
DISPLAY INVISIBLE (775 3750);
FORCEPROP 1 LAST CDS_LMAN_SYM_OUTLINE -175,100,175,-100
J 0
(775 3750);
DISPLAY 0.468085 (775 3750);
PAINT GREEN (775 3750);
DISPLAY INVISIBLE (775 3750);
FORCEPROP 1 LAST PATH I16
J 0
(775 3750);
DISPLAY 0.723404 (775 3750);
PAINT GREEN (775 3750);
DISPLAY INVISIBLE (775 3750);
FORCEPROP 1 LAST PART_NUMBER AL002G07003
J 0
(606 3984);
DISPLAY 0.723404 (606 3984);
PAINT GREEN (606 3984);
DISPLAY INVISIBLE (606 3984);
FORCEADD UNIVERSAL_GND..1
(200 3600);
FORCEPROP 3 LASTPIN (200 3650) SIG_NAME GND\g
J 0
(210 3660);
DISPLAY 0.659574 (210 3660);
PAINT MONO (210 3660);
DISPLAY INVISIBLE (210 3660);
FORCEPROP 2 LAST CDS_LIB pure_quanta_power
J 0
(200 3600);
DISPLAY INVISIBLE (200 3600);
FORCEPROP 1 LAST HDL_POWER GND
J 1
(225 3525);
DISPLAY 0.872340 (225 3525);
PAINT GREEN (225 3525);
DISPLAY INVISIBLE (225 3525);
FORCEPROP 1 LAST PATH I17
J 0
(275 3600);
DISPLAY 0.872340 (275 3600);
PAINT AQUA (275 3600);
DISPLAY INVISIBLE (275 3600);
FORCEADD UNIVERSAL_POWER..1
(-650 4825);
FORCEPROP 3 LASTPIN (-650 4775) SIG_NAME P3V3_AUX\g
J 0
(-640 4785);
DISPLAY 0.659574 (-640 4785);
PAINT MONO (-640 4785);
DISPLAY INVISIBLE (-640 4785);
FORCEPROP 1 LAST HDL_POWER P3V3_AUX
J 1
(-650 4875);
DISPLAY 0.872340 (-650 4875);
PAINT GREEN (-650 4875);
FORCEPROP 2 LAST CDS_LIB pure_quanta_power
J 0
(-650 4825);
PAINT MONO (-650 4825);
DISPLAY INVISIBLE (-650 4825);
FORCEPROP 1 LAST PATH I28
J 0
(-600 4850);
DISPLAY 0.872340 (-600 4850);
PAINT AQUA (-600 4850);
DISPLAY INVISIBLE (-600 4850);
FORCEADD UNIVERSAL_GND..1
(-625 3900);
FORCEPROP 3 LASTPIN (-625 3950) SIG_NAME GND\g
J 0
(-615 3960);
DISPLAY 0.659574 (-615 3960);
PAINT MONO (-615 3960);
DISPLAY INVISIBLE (-615 3960);
FORCEPROP 2 LAST CDS_LIB pure_quanta_power
J 0
(-625 3900);
DISPLAY INVISIBLE (-625 3900);
FORCEPROP 1 LAST HDL_POWER GND
J 1
(-600 3825);
DISPLAY 0.872340 (-600 3825);
PAINT GREEN (-600 3825);
DISPLAY INVISIBLE (-600 3825);
FORCEPROP 1 LAST PATH I30
J 0
(-550 3900);
DISPLAY 0.872340 (-550 3900);
PAINT AQUA (-550 3900);
DISPLAY INVISIBLE (-550 3900);
FORCEADD Q_RES..2
(-625 4100);
FORCEPROP 1 LAST LOCATION R3460
J 0
(-580 4225);
DISPLAY 0.978723 (-580 4225);
FORCEPROP 0 LAST $SEC 1
J 0
(-575 4275);
DISPLAY 0.680851 (-575 4275);
PAINT MONO (-575 4275);
DISPLAY INVISIBLE (-575 4275);
FORCEPROP 0 LAST CDS_SEC 1
J 0
(-575 4275);
DISPLAY 1.021277 (-575 4275);
DISPLAY INVISIBLE (-575 4275);
FORCEPROP 1 LASTPIN (-625 4200) $PN 1
J 0
(-620 4162);
DISPLAY 0.787234 (-620 4162);
PAINT MONO (-620 4162);
FORCEPROP 1 LASTPIN (-625 4000) $PN 2
J 0
(-620 4010);
DISPLAY 0.787234 (-620 4010);
PAINT MONO (-620 4010);
FORCEPROP 1 LAST TOLERANCE 1%
J 0
(-580 4125);
DISPLAY 0.510638 (-580 4125);
FORCEPROP 1 LAST VALUE 100K
J 0
(-580 4175);
DISPLAY 0.510638 (-580 4175);
FORCEPROP 1 LAST WATTAGE 1/16W
J 0
(-585 4075);
DISPLAY 0.510638 (-585 4075);
FORCEPROP 1 LAST PACK_TYPE 0402LF
J 0
(-585 3925);
DISPLAY 0.510638 (-585 3925);
FORCEPROP 1 LAST MATERIAL EMPTY
J 0
(-585 4025);
DISPLAY 0.510638 (-585 4025);
PAINT RED (-585 4025);
FORCEPROP 2 LAST CDS_LIB pure_quanta
J 0
(-625 4100);
DISPLAY INVISIBLE (-625 4100);
FORCEPROP 1 LAST PATH I31
J 0
(-575 4275);
DISPLAY 0.978723 (-575 4275);
PAINT WHITE (-575 4275);
DISPLAY INVISIBLE (-575 4275);
FORCEPROP 1 LAST PART_NUMBER CS41002FB09
J 0
(-585 3975);
DISPLAY 0.510638 (-585 3975);
DISPLAY INVISIBLE (-585 3975);
FORCEADD OFFPAGE..4
R 2
(-900 4300);
FORCEPROP 2 LAST $XR0 81 
J 0
(-1121 4300);
DISPLAY 0.638298 (-1121 4300);
PAINT MONO (-1121 4300);
FORCEPROP 2 LAST CDS_LIB standard
J 0
(-900 4300);
DISPLAY INVISIBLE (-900 4300);
FORCEPROP 1 LAST OFFPAGE TRUE
J 2
(-1225 4175);
DISPLAY 0.872340 (-1225 4175);
PAINT GREEN (-1225 4175);
DISPLAY INVISIBLE (-1225 4175);
FORCEPROP 1 LAST COMMENT_BODY TRUE
J 2
(-875 4200);
DISPLAY 0.872340 (-875 4200);
PAINT GREEN (-875 4200);
DISPLAY INVISIBLE (-875 4200);
FORCEPROP 2 LAST PATH I32
J 0
(-1175 4350);
DISPLAY 1.021277 (-1175 4350);
DISPLAY INVISIBLE (-1175 4350);
FORCEADD Q_RES..2
(1875 4000);
FORCEPROP 1 LAST LOCATION R3462
J 0
(1920 4125);
DISPLAY 0.978723 (1920 4125);
FORCEPROP 0 LAST $SEC 1
J 0
(1925 4175);
DISPLAY 0.680851 (1925 4175);
PAINT MONO (1925 4175);
DISPLAY INVISIBLE (1925 4175);
FORCEPROP 0 LAST CDS_SEC 1
J 0
(1925 4175);
DISPLAY 1.021277 (1925 4175);
DISPLAY INVISIBLE (1925 4175);
FORCEPROP 1 LASTPIN (1875 4100) $PN 1
J 0
(1880 4062);
DISPLAY 0.787234 (1880 4062);
PAINT MONO (1880 4062);
FORCEPROP 1 LASTPIN (1875 3900) $PN 2
J 0
(1880 3910);
DISPLAY 0.787234 (1880 3910);
PAINT MONO (1880 3910);
FORCEPROP 1 LAST PACK_TYPE 0402LF
J 0
(1915 3825);
DISPLAY 0.510638 (1915 3825);
FORCEPROP 1 LAST MATERIAL EMPTY
J 0
(1915 3925);
DISPLAY 0.510638 (1915 3925);
PAINT RED (1915 3925);
FORCEPROP 1 LAST WATTAGE 1/16W
J 0
(1915 3975);
DISPLAY 0.510638 (1915 3975);
FORCEPROP 1 LAST TOLERANCE 1%
J 0
(1920 4025);
DISPLAY 0.510638 (1920 4025);
FORCEPROP 1 LAST VALUE 100K
J 0
(1920 4075);
DISPLAY 0.510638 (1920 4075);
FORCEPROP 2 LAST CDS_LIB pure_quanta
J 0
(1875 4000);
DISPLAY INVISIBLE (1875 4000);
FORCEPROP 1 LAST PATH I33
J 0
(1925 4175);
DISPLAY 0.978723 (1925 4175);
PAINT WHITE (1925 4175);
DISPLAY INVISIBLE (1925 4175);
FORCEPROP 1 LAST PART_NUMBER CS41002FB09
J 0
(1915 3875);
DISPLAY 0.510638 (1915 3875);
DISPLAY INVISIBLE (1915 3875);
FORCEADD UNIVERSAL_POWER..1
(1850 4850);
FORCEPROP 3 LASTPIN (1850 4800) SIG_NAME P3V3_AUX\g
J 0
(1860 4810);
DISPLAY 0.659574 (1860 4810);
PAINT MONO (1860 4810);
DISPLAY INVISIBLE (1860 4810);
FORCEPROP 1 LAST HDL_POWER P3V3_AUX
J 1
(1850 4900);
DISPLAY 0.872340 (1850 4900);
PAINT GREEN (1850 4900);
FORCEPROP 2 LAST CDS_LIB pure_quanta_power
J 0
(1850 4850);
PAINT MONO (1850 4850);
DISPLAY INVISIBLE (1850 4850);
FORCEPROP 1 LAST PATH I34
J 0
(1900 4875);
DISPLAY 0.872340 (1900 4875);
PAINT AQUA (1900 4875);
DISPLAY INVISIBLE (1900 4875);
FORCEADD Q_RES..2
(1850 4600);
FORCEPROP 1 LAST LOCATION R3461
J 0
(1895 4725);
DISPLAY 0.787234 (1895 4725);
FORCEPROP 0 LAST $SEC 1
J 0
(1900 4775);
DISPLAY 0.680851 (1900 4775);
PAINT MONO (1900 4775);
DISPLAY INVISIBLE (1900 4775);
FORCEPROP 0 LAST CDS_SEC 1
J 0
(1900 4775);
DISPLAY 1.021277 (1900 4775);
DISPLAY INVISIBLE (1900 4775);
FORCEPROP 1 LASTPIN (1850 4700) $PN 1
J 0
(1855 4662);
DISPLAY 0.787234 (1855 4662);
PAINT MONO (1855 4662);
FORCEPROP 1 LASTPIN (1850 4500) $PN 2
J 0
(1855 4510);
DISPLAY 0.787234 (1855 4510);
PAINT MONO (1855 4510);
FORCEPROP 1 LAST WATTAGE 1/16W
J 0
(1890 4575);
DISPLAY 0.787234 (1890 4575);
FORCEPROP 1 LAST VALUE 54.9K
J 0
(1895 4675);
DISPLAY 0.787234 (1895 4675);
FORCEPROP 1 LAST TOLERANCE 1%
J 0
(1895 4625);
DISPLAY 0.787234 (1895 4625);
FORCEPROP 1 LAST MATERIAL CHIP
J 0
(1890 4525);
DISPLAY 0.787234 (1890 4525);
FORCEPROP 1 LAST PACK_TYPE 0402LF
J 0
(1890 4425);
DISPLAY 0.787234 (1890 4425);
FORCEPROP 2 LAST CDS_LIB pure_quanta
J 0
(1850 4600);
DISPLAY INVISIBLE (1850 4600);
FORCEPROP 1 LAST PATH I35
J 0
(1900 4775);
DISPLAY 0.978723 (1900 4775);
PAINT WHITE (1900 4775);
DISPLAY INVISIBLE (1900 4775);
FORCEPROP 1 LAST PART_NUMBER CS35492FB03
J 0
(1890 4475);
DISPLAY 0.787234 (1890 4475);
DISPLAY INVISIBLE (1890 4475);
FORCEADD OFFPAGE..2
(3375 4300);
FORCEPROP 2 LAST $XR0 122 
J 0
(3564 4300);
DISPLAY 0.638298 (3564 4300);
PAINT MONO (3564 4300);
FORCEPROP 2 LAST CDS_LIB standard
J 0
(3375 4300);
DISPLAY INVISIBLE (3375 4300);
FORCEPROP 1 LAST OFFPAGE TRUE
J 0
(3700 4175);
DISPLAY 0.872340 (3700 4175);
PAINT AQUA (3700 4175);
DISPLAY INVISIBLE (3700 4175);
FORCEPROP 1 LAST COMMENT_BODY TRUE
J 0
(3330 4205);
DISPLAY 0.872340 (3330 4205);
PAINT GREEN (3330 4205);
DISPLAY INVISIBLE (3330 4205);
FORCEPROP 2 LAST PATH I36
J 0
(3575 4350);
DISPLAY 1.021277 (3575 4350);
DISPLAY INVISIBLE (3575 4350);
FORCEADD Q_RES..1
(2100 4300);
FORCEPROP 1 LAST LOCATION R3397
J 0
(1900 4300);
DISPLAY 0.723404 (1900 4300);
FORCEPROP 2 LAST $SEC 1
J 0
(2050 4500);
DISPLAY 0.680851 (2050 4500);
PAINT MONO (2050 4500);
DISPLAY INVISIBLE (2050 4500);
FORCEPROP 0 LAST CDS_SEC 1
J 0
(1800 4375);
DISPLAY INVISIBLE (1800 4375);
FORCEPROP 1 LASTPIN (2000 4300) $PN 1
J 0
(2012 4312);
DISPLAY 0.723404 (2012 4312);
PAINT MONO (2012 4312);
FORCEPROP 1 LASTPIN (2200 4300) $PN 2
J 0
(2162 4312);
DISPLAY 0.723404 (2162 4312);
PAINT MONO (2162 4312);
FORCEPROP 1 LAST VALUE 33.2
J 2
(2350 4300);
DISPLAY 0.723404 (2350 4300);
FORCEPROP 1 LAST PACK_TYPE 0402LF
J 0
(1925 4250);
DISPLAY 0.723404 (1925 4250);
FORCEPROP 1 LAST MATERIAL CHIP
J 0
(2125 4250);
DISPLAY 0.723404 (2125 4250);
FORCEPROP 2 LAST CDS_LIB pure_quanta
J 0
(2100 4300);
DISPLAY INVISIBLE (2100 4300);
FORCEPROP 1 LAST TOLERANCE 1%
J 0
(2575 4300);
DISPLAY 0.723404 (2575 4300);
PAINT SKYBLUE (2575 4300);
DISPLAY INVISIBLE (2575 4300);
FORCEPROP 1 LAST WATTAGE 1/16W
J 2
(2500 4250);
DISPLAY 0.723404 (2500 4250);
PAINT SKYBLUE (2500 4250);
DISPLAY INVISIBLE (2500 4250);
FORCEPROP 1 LAST PATH I37
J 0
(2050 4450);
DISPLAY 0.978723 (2050 4450);
PAINT WHITE (2050 4450);
DISPLAY INVISIBLE (2050 4450);
FORCEPROP 1 LAST PART_NUMBER CS03322FB03
J 0
(1700 4200);
DISPLAY 0.723404 (1700 4200);
PAINT WHITE (1700 4200);
DISPLAY INVISIBLE (1700 4200);
FORCEADD UNIVERSAL_GND..1
(1875 3800);
FORCEPROP 3 LASTPIN (1875 3850) SIG_NAME GND\g
J 0
(1885 3860);
DISPLAY 0.659574 (1885 3860);
PAINT MONO (1885 3860);
DISPLAY INVISIBLE (1885 3860);
FORCEPROP 2 LAST CDS_LIB pure_quanta_power
J 0
(1875 3800);
DISPLAY INVISIBLE (1875 3800);
FORCEPROP 1 LAST HDL_POWER GND
J 1
(1900 3725);
DISPLAY 0.872340 (1900 3725);
PAINT GREEN (1900 3725);
DISPLAY INVISIBLE (1900 3725);
FORCEPROP 1 LAST PATH I38
J 0
(1950 3800);
DISPLAY 0.872340 (1950 3800);
PAINT AQUA (1950 3800);
DISPLAY INVISIBLE (1950 3800);
FORCEADD UNIVERSAL_POWER..1
(-650 3675);
FORCEPROP 3 LASTPIN (-650 3625) SIG_NAME P3V3_AUX\g
J 0
(-640 3635);
DISPLAY 0.659574 (-640 3635);
PAINT MONO (-640 3635);
DISPLAY INVISIBLE (-640 3635);
FORCEPROP 1 LAST HDL_POWER P3V3_AUX
J 1
(-650 3725);
DISPLAY 0.872340 (-650 3725);
PAINT GREEN (-650 3725);
FORCEPROP 2 LAST CDS_LIB pure_quanta_power
J 0
(-650 3675);
PAINT MONO (-650 3675);
DISPLAY INVISIBLE (-650 3675);
FORCEPROP 1 LAST PATH I39
J 0
(-600 3700);
DISPLAY 0.872340 (-600 3700);
PAINT AQUA (-600 3700);
DISPLAY INVISIBLE (-600 3700);
FORCEADD Q_RES..2
(-650 3425);
FORCEPROP 1 LAST LOCATION R3488
J 0
(-605 3550);
DISPLAY 0.978723 (-605 3550);
FORCEPROP 0 LAST $SEC 1
J 0
(-600 3600);
DISPLAY 0.680851 (-600 3600);
PAINT MONO (-600 3600);
DISPLAY INVISIBLE (-600 3600);
FORCEPROP 0 LAST CDS_SEC 1
J 0
(-600 3600);
DISPLAY 1.021277 (-600 3600);
DISPLAY INVISIBLE (-600 3600);
FORCEPROP 1 LASTPIN (-650 3525) $PN 1
J 0
(-645 3487);
DISPLAY 0.787234 (-645 3487);
PAINT MONO (-645 3487);
FORCEPROP 1 LASTPIN (-650 3325) $PN 2
J 0
(-645 3335);
DISPLAY 0.787234 (-645 3335);
PAINT MONO (-645 3335);
FORCEPROP 1 LAST WATTAGE 1/16W
J 0
(-610 3400);
DISPLAY 0.638298 (-610 3400);
FORCEPROP 1 LAST MATERIAL CHIP
J 0
(-610 3350);
DISPLAY 0.638298 (-610 3350);
FORCEPROP 1 LAST PACK_TYPE 0402LF
J 0
(-610 3300);
DISPLAY 0.638298 (-610 3300);
FORCEPROP 1 LAST VALUE 1K
J 0
(-605 3500);
DISPLAY 0.638298 (-605 3500);
FORCEPROP 1 LAST TOLERANCE 1%
J 0
(-605 3450);
DISPLAY 0.638298 (-605 3450);
FORCEPROP 2 LAST CDS_LIB pure_quanta
J 0
(-650 3425);
DISPLAY INVISIBLE (-650 3425);
FORCEPROP 1 LAST PATH I40
J 0
(-600 3600);
DISPLAY 0.978723 (-600 3600);
PAINT WHITE (-600 3600);
DISPLAY INVISIBLE (-600 3600);
FORCEPROP 1 LAST PART_NUMBER CS21002FB06
J 0
(-610 3250);
DISPLAY 0.638298 (-610 3250);
DISPLAY INVISIBLE (-610 3250);
FORCEADD OFFPAGE..4
R 2
(-900 3150);
FORCEPROP 2 LAST $XR0 81 
J 0
(-1121 3150);
DISPLAY 0.638298 (-1121 3150);
PAINT MONO (-1121 3150);
FORCEPROP 2 LAST CDS_LIB standard
J 0
(-900 3150);
DISPLAY INVISIBLE (-900 3150);
FORCEPROP 1 LAST OFFPAGE TRUE
J 2
(-1225 3025);
DISPLAY 0.872340 (-1225 3025);
PAINT GREEN (-1225 3025);
DISPLAY INVISIBLE (-1225 3025);
FORCEPROP 1 LAST COMMENT_BODY TRUE
J 2
(-875 3050);
DISPLAY 0.872340 (-875 3050);
PAINT GREEN (-875 3050);
DISPLAY INVISIBLE (-875 3050);
FORCEPROP 2 LAST PATH I41
J 0
(-1150 3200);
DISPLAY 1.021277 (-1150 3200);
DISPLAY INVISIBLE (-1150 3200);
FORCEADD Q_RES..2
(-625 2950);
FORCEPROP 1 LAST LOCATION R3489
J 0
(-580 3075);
DISPLAY 0.978723 (-580 3075);
FORCEPROP 0 LAST $SEC 1
J 0
(-575 3125);
DISPLAY 0.680851 (-575 3125);
PAINT MONO (-575 3125);
DISPLAY INVISIBLE (-575 3125);
FORCEPROP 0 LAST CDS_SEC 1
J 0
(-575 3125);
DISPLAY 1.021277 (-575 3125);
DISPLAY INVISIBLE (-575 3125);
FORCEPROP 1 LASTPIN (-625 3050) $PN 1
J 0
(-620 3012);
DISPLAY 0.787234 (-620 3012);
PAINT MONO (-620 3012);
FORCEPROP 1 LASTPIN (-625 2850) $PN 2
J 0
(-620 2860);
DISPLAY 0.787234 (-620 2860);
PAINT MONO (-620 2860);
FORCEPROP 1 LAST MATERIAL EMPTY
J 0
(-585 2875);
DISPLAY 0.510638 (-585 2875);
PAINT RED (-585 2875);
FORCEPROP 1 LAST PACK_TYPE 0402LF
J 0
(-585 2775);
DISPLAY 0.510638 (-585 2775);
FORCEPROP 1 LAST WATTAGE 1/16W
J 0
(-585 2925);
DISPLAY 0.510638 (-585 2925);
FORCEPROP 1 LAST VALUE 100K
J 0
(-580 3025);
DISPLAY 0.510638 (-580 3025);
FORCEPROP 1 LAST TOLERANCE 1%
J 0
(-580 2975);
DISPLAY 0.510638 (-580 2975);
FORCEPROP 2 LAST CDS_LIB pure_quanta
J 0
(-625 2950);
DISPLAY INVISIBLE (-625 2950);
FORCEPROP 1 LAST PATH I42
J 0
(-575 3125);
DISPLAY 0.978723 (-575 3125);
PAINT WHITE (-575 3125);
DISPLAY INVISIBLE (-575 3125);
FORCEPROP 1 LAST PART_NUMBER CS41002FB09
J 0
(-585 2825);
DISPLAY 0.510638 (-585 2825);
DISPLAY INVISIBLE (-585 2825);
FORCEADD UNIVERSAL_GND..1
(-625 2750);
FORCEPROP 3 LASTPIN (-625 2800) SIG_NAME GND\g
J 0
(-615 2810);
DISPLAY 0.659574 (-615 2810);
PAINT MONO (-615 2810);
DISPLAY INVISIBLE (-615 2810);
FORCEPROP 2 LAST CDS_LIB pure_quanta_power
J 0
(-625 2750);
DISPLAY INVISIBLE (-625 2750);
FORCEPROP 1 LAST HDL_POWER GND
J 1
(-600 2675);
DISPLAY 0.872340 (-600 2675);
PAINT GREEN (-600 2675);
DISPLAY INVISIBLE (-600 2675);
FORCEPROP 1 LAST PATH I43
J 0
(-550 2750);
DISPLAY 0.872340 (-550 2750);
PAINT AQUA (-550 2750);
DISPLAY INVISIBLE (-550 2750);
FORCEADD OFFPAGE..2
(3425 3100);
FORCEPROP 2 LAST $XR0 120 
J 0
(3614 3100);
DISPLAY 0.638298 (3614 3100);
PAINT MONO (3614 3100);
FORCEPROP 2 LAST CDS_LIB standard
J 0
(3425 3100);
DISPLAY INVISIBLE (3425 3100);
FORCEPROP 1 LAST OFFPAGE TRUE
J 0
(3750 2975);
DISPLAY 0.872340 (3750 2975);
PAINT AQUA (3750 2975);
DISPLAY INVISIBLE (3750 2975);
FORCEPROP 1 LAST COMMENT_BODY TRUE
J 0
(3380 3005);
DISPLAY 0.872340 (3380 3005);
PAINT GREEN (3380 3005);
DISPLAY INVISIBLE (3380 3005);
FORCEPROP 2 LAST PATH I44
J 0
(3600 3175);
DISPLAY 1.021277 (3600 3175);
DISPLAY INVISIBLE (3600 3175);
FORCEADD Q_RES..1
(2150 3100);
FORCEPROP 1 LAST LOCATION R3496
J 0
(1925 3100);
DISPLAY 0.723404 (1925 3100);
FORCEPROP 2 LAST $SEC 1
J 0
(2100 3300);
DISPLAY 0.680851 (2100 3300);
PAINT MONO (2100 3300);
DISPLAY INVISIBLE (2100 3300);
FORCEPROP 0 LAST CDS_SEC 1
J 0
(1850 3175);
DISPLAY INVISIBLE (1850 3175);
FORCEPROP 1 LASTPIN (2050 3100) $PN 1
J 0
(2062 3112);
DISPLAY 0.723404 (2062 3112);
PAINT MONO (2062 3112);
FORCEPROP 1 LASTPIN (2250 3100) $PN 2
J 0
(2212 3112);
DISPLAY 0.723404 (2212 3112);
PAINT MONO (2212 3112);
FORCEPROP 1 LAST VALUE 33.2
J 2
(2400 3100);
DISPLAY 0.723404 (2400 3100);
FORCEPROP 1 LAST PACK_TYPE 0402LF
J 0
(1975 3050);
DISPLAY 0.723404 (1975 3050);
FORCEPROP 1 LAST MATERIAL CHIP
J 0
(2175 3050);
DISPLAY 0.723404 (2175 3050);
FORCEPROP 2 LAST CDS_LIB pure_quanta
J 0
(2150 3100);
DISPLAY INVISIBLE (2150 3100);
FORCEPROP 1 LAST TOLERANCE 1%
J 0
(2625 3100);
DISPLAY 0.723404 (2625 3100);
PAINT SKYBLUE (2625 3100);
DISPLAY INVISIBLE (2625 3100);
FORCEPROP 1 LAST WATTAGE 1/16W
J 2
(2550 3050);
DISPLAY 0.723404 (2550 3050);
PAINT SKYBLUE (2550 3050);
DISPLAY INVISIBLE (2550 3050);
FORCEPROP 1 LAST PATH I45
J 0
(2100 3250);
DISPLAY 0.978723 (2100 3250);
PAINT WHITE (2100 3250);
DISPLAY INVISIBLE (2100 3250);
FORCEPROP 1 LAST PART_NUMBER CS03322FB03
J 0
(1750 3000);
DISPLAY 0.723404 (1750 3000);
PAINT WHITE (1750 3000);
DISPLAY INVISIBLE (1750 3000);
FORCEADD UNIVERSAL_POWER..1
(1900 3650);
FORCEPROP 3 LASTPIN (1900 3600) SIG_NAME P3V3_AUX\g
J 0
(1910 3610);
DISPLAY 0.659574 (1910 3610);
PAINT MONO (1910 3610);
DISPLAY INVISIBLE (1910 3610);
FORCEPROP 1 LAST HDL_POWER P3V3_AUX
J 1
(1900 3700);
DISPLAY 0.872340 (1900 3700);
PAINT GREEN (1900 3700);
FORCEPROP 2 LAST CDS_LIB pure_quanta_power
J 0
(1900 3650);
PAINT MONO (1900 3650);
DISPLAY INVISIBLE (1900 3650);
FORCEPROP 1 LAST PATH I46
J 0
(1950 3675);
DISPLAY 0.872340 (1950 3675);
PAINT AQUA (1950 3675);
DISPLAY INVISIBLE (1950 3675);
FORCEADD Q_RES..2
(1900 3400);
FORCEPROP 1 LAST LOCATION R3492
J 0
(1945 3525);
DISPLAY 0.787234 (1945 3525);
FORCEPROP 0 LAST $SEC 1
J 0
(1950 3575);
DISPLAY 0.680851 (1950 3575);
PAINT MONO (1950 3575);
DISPLAY INVISIBLE (1950 3575);
FORCEPROP 0 LAST CDS_SEC 1
J 0
(1950 3575);
DISPLAY 1.021277 (1950 3575);
DISPLAY INVISIBLE (1950 3575);
FORCEPROP 1 LASTPIN (1900 3500) $PN 1
J 0
(1905 3462);
DISPLAY 0.787234 (1905 3462);
PAINT MONO (1905 3462);
FORCEPROP 1 LASTPIN (1900 3300) $PN 2
J 0
(1905 3310);
DISPLAY 0.787234 (1905 3310);
PAINT MONO (1905 3310);
FORCEPROP 1 LAST WATTAGE 1/16W
J 0
(1940 3375);
DISPLAY 0.787234 (1940 3375);
FORCEPROP 1 LAST VALUE 54.9K
J 0
(1945 3475);
DISPLAY 0.787234 (1945 3475);
FORCEPROP 1 LAST TOLERANCE 1%
J 0
(1945 3425);
DISPLAY 0.787234 (1945 3425);
FORCEPROP 1 LAST MATERIAL CHIP
J 0
(1940 3325);
DISPLAY 0.787234 (1940 3325);
FORCEPROP 1 LAST PACK_TYPE 0402LF
J 0
(1940 3225);
DISPLAY 0.787234 (1940 3225);
FORCEPROP 2 LAST CDS_LIB pure_quanta
J 0
(1900 3400);
DISPLAY INVISIBLE (1900 3400);
FORCEPROP 1 LAST PATH I47
J 0
(1950 3575);
DISPLAY 0.978723 (1950 3575);
PAINT WHITE (1950 3575);
DISPLAY INVISIBLE (1950 3575);
FORCEPROP 1 LAST PART_NUMBER CS35492FB03
J 0
(1940 3275);
DISPLAY 0.787234 (1940 3275);
DISPLAY INVISIBLE (1940 3275);
FORCEADD Q_RES..2
(1925 2800);
FORCEPROP 1 LAST LOCATION R3493
J 0
(1970 2925);
DISPLAY 0.978723 (1970 2925);
FORCEPROP 0 LAST $SEC 1
J 0
(1975 2975);
DISPLAY 0.680851 (1975 2975);
PAINT MONO (1975 2975);
DISPLAY INVISIBLE (1975 2975);
FORCEPROP 0 LAST CDS_SEC 1
J 0
(1975 2975);
DISPLAY 1.021277 (1975 2975);
DISPLAY INVISIBLE (1975 2975);
FORCEPROP 1 LASTPIN (1925 2900) $PN 1
J 0
(1930 2862);
DISPLAY 0.787234 (1930 2862);
PAINT MONO (1930 2862);
FORCEPROP 1 LASTPIN (1925 2700) $PN 2
J 0
(1930 2710);
DISPLAY 0.787234 (1930 2710);
PAINT MONO (1930 2710);
FORCEPROP 1 LAST WATTAGE 1/16W
J 0
(1965 2775);
DISPLAY 0.510638 (1965 2775);
FORCEPROP 1 LAST TOLERANCE 1%
J 0
(1970 2825);
DISPLAY 0.510638 (1970 2825);
FORCEPROP 1 LAST VALUE 100K
J 0
(1970 2875);
DISPLAY 0.510638 (1970 2875);
FORCEPROP 1 LAST MATERIAL EMPTY
J 0
(1965 2725);
DISPLAY 0.510638 (1965 2725);
PAINT RED (1965 2725);
FORCEPROP 1 LAST PACK_TYPE 0402LF
J 0
(1965 2625);
DISPLAY 0.510638 (1965 2625);
FORCEPROP 2 LAST CDS_LIB pure_quanta
J 0
(1925 2800);
DISPLAY INVISIBLE (1925 2800);
FORCEPROP 1 LAST PATH I48
J 0
(1975 2975);
DISPLAY 0.978723 (1975 2975);
PAINT WHITE (1975 2975);
DISPLAY INVISIBLE (1975 2975);
FORCEPROP 1 LAST PART_NUMBER CS41002FB09
J 0
(1965 2675);
DISPLAY 0.510638 (1965 2675);
DISPLAY INVISIBLE (1965 2675);
FORCEADD UNIVERSAL_GND..1
(1925 2600);
FORCEPROP 3 LASTPIN (1925 2650) SIG_NAME GND\g
J 0
(1935 2660);
DISPLAY 0.659574 (1935 2660);
PAINT MONO (1935 2660);
DISPLAY INVISIBLE (1935 2660);
FORCEPROP 2 LAST CDS_LIB pure_quanta_power
J 0
(1925 2600);
DISPLAY INVISIBLE (1925 2600);
FORCEPROP 1 LAST HDL_POWER GND
J 1
(1950 2525);
DISPLAY 0.872340 (1950 2525);
PAINT GREEN (1950 2525);
DISPLAY INVISIBLE (1950 2525);
FORCEPROP 1 LAST PATH I49
J 0
(2000 2600);
DISPLAY 0.872340 (2000 2600);
PAINT AQUA (2000 2600);
DISPLAY INVISIBLE (2000 2600);
FORCEADD 74LVC2G07DW7..1
(775 1250);
FORCEPROP 1 LAST LOCATION U257
J 0
(606 1631);
DISPLAY 0.723404 (606 1631);
PAINT GREEN (606 1631);
FORCEPROP 0 LAST $SEC 1
J 0
(625 1775);
DISPLAY 0.680851 (625 1775);
PAINT MONO (625 1775);
DISPLAY INVISIBLE (625 1775);
FORCEPROP 0 LAST CDS_SEC 1
J 0
(625 1775);
DISPLAY 1.021277 (625 1775);
DISPLAY INVISIBLE (625 1775);
FORCEPROP 0 LASTPIN (450 1300) $PN 1
J 2
(440 1310);
DISPLAY 0.680851 (440 1310);
PAINT MONO (440 1310);
FORCEPROP 0 LASTPIN (1100 1300) $PN 6
J 0
(1110 1310);
DISPLAY 0.680851 (1110 1310);
PAINT MONO (1110 1310);
FORCEPROP 0 LASTPIN (450 1200) $PN 3
J 2
(440 1210);
DISPLAY 0.680851 (440 1210);
PAINT MONO (440 1210);
FORCEPROP 0 LASTPIN (1100 1200) $PN 4
J 0
(1110 1210);
DISPLAY 0.680851 (1110 1210);
PAINT MONO (1110 1210);
FORCEPROP 0 LASTPIN (450 1250) $PN 2
J 2
(440 1260);
DISPLAY 0.680851 (440 1260);
PAINT MONO (440 1260);
FORCEPROP 0 LASTPIN (1100 1250) $PN 5
J 0
(1110 1260);
DISPLAY 0.680851 (1110 1260);
PAINT MONO (1110 1260);
FORCEPROP 2 LAST PART_TYPE SMLF
J 0
(625 1725);
DISPLAY 1.021277 (625 1725);
FORCEPROP 2 LAST VALUE 74LVC2G07DW-7
J 0
(475 1550);
DISPLAY 1.021277 (475 1550);
FORCEPROP 1 LAST MATERIAL IC
J 0
(606 1357);
DISPLAY 0.723404 (606 1357);
PAINT GREEN (606 1357);
FORCEPROP 2 LAST CDS_LIB pure_quanta
J 0
(775 1250);
DISPLAY INVISIBLE (775 1250);
FORCEPROP 1 LAST NEEDS_NO_SIZE TRUE
J 0
(775 1250);
DISPLAY 0.723404 (775 1250);
PAINT GREEN (775 1250);
DISPLAY INVISIBLE (775 1250);
FORCEPROP 1 LAST CDS_LMAN_SYM_OUTLINE -175,100,175,-100
J 0
(775 1250);
DISPLAY 0.468085 (775 1250);
PAINT GREEN (775 1250);
DISPLAY INVISIBLE (775 1250);
FORCEPROP 1 LAST PATH I50
J 0
(775 1250);
DISPLAY 0.723404 (775 1250);
PAINT GREEN (775 1250);
DISPLAY INVISIBLE (775 1250);
FORCEPROP 1 LAST PART_NUMBER AL002G07003
J 0
(606 1484);
DISPLAY 0.723404 (606 1484);
PAINT GREEN (606 1484);
DISPLAY INVISIBLE (606 1484);
FORCEADD OFFPAGE..2
(3600 1800);
FORCEPROP 2 LAST $XR0 120 
J 0
(3789 1800);
DISPLAY 0.638298 (3789 1800);
PAINT MONO (3789 1800);
FORCEPROP 2 LAST CDS_LIB standard
J 0
(3600 1800);
DISPLAY INVISIBLE (3600 1800);
FORCEPROP 1 LAST OFFPAGE TRUE
J 0
(3925 1675);
DISPLAY 0.872340 (3925 1675);
PAINT AQUA (3925 1675);
DISPLAY INVISIBLE (3925 1675);
FORCEPROP 1 LAST COMMENT_BODY TRUE
J 0
(3555 1705);
DISPLAY 0.872340 (3555 1705);
PAINT GREEN (3555 1705);
DISPLAY INVISIBLE (3555 1705);
FORCEPROP 2 LAST PATH I51
J 0
(3775 1875);
DISPLAY 1.021277 (3775 1875);
DISPLAY INVISIBLE (3775 1875);
FORCEADD Q_RES..1
(2325 1800);
FORCEPROP 1 LAST LOCATION R3497
J 0
(2125 1800);
DISPLAY 0.723404 (2125 1800);
FORCEPROP 2 LAST $SEC 1
J 0
(2275 2000);
DISPLAY 0.680851 (2275 2000);
PAINT MONO (2275 2000);
DISPLAY INVISIBLE (2275 2000);
FORCEPROP 0 LAST CDS_SEC 1
J 0
(2025 1875);
DISPLAY INVISIBLE (2025 1875);
FORCEPROP 1 LASTPIN (2225 1800) $PN 1
J 0
(2237 1812);
DISPLAY 0.723404 (2237 1812);
PAINT MONO (2237 1812);
FORCEPROP 1 LASTPIN (2425 1800) $PN 2
J 0
(2387 1812);
DISPLAY 0.723404 (2387 1812);
PAINT MONO (2387 1812);
FORCEPROP 1 LAST VALUE 33.2
J 2
(2575 1800);
DISPLAY 0.723404 (2575 1800);
FORCEPROP 1 LAST PACK_TYPE 0402LF
J 0
(2150 1750);
DISPLAY 0.723404 (2150 1750);
FORCEPROP 1 LAST MATERIAL CHIP
J 0
(2350 1750);
DISPLAY 0.723404 (2350 1750);
FORCEPROP 2 LAST CDS_LIB pure_quanta
J 0
(2325 1800);
DISPLAY INVISIBLE (2325 1800);
FORCEPROP 1 LAST TOLERANCE 1%
J 0
(2800 1800);
DISPLAY 0.723404 (2800 1800);
PAINT SKYBLUE (2800 1800);
DISPLAY INVISIBLE (2800 1800);
FORCEPROP 1 LAST WATTAGE 1/16W
J 2
(2725 1750);
DISPLAY 0.723404 (2725 1750);
PAINT SKYBLUE (2725 1750);
DISPLAY INVISIBLE (2725 1750);
FORCEPROP 1 LAST PATH I53
J 0
(2275 1950);
DISPLAY 0.978723 (2275 1950);
PAINT WHITE (2275 1950);
DISPLAY INVISIBLE (2275 1950);
FORCEPROP 1 LAST PART_NUMBER CS03322FB03
J 0
(1925 1700);
DISPLAY 0.723404 (1925 1700);
PAINT WHITE (1925 1700);
DISPLAY INVISIBLE (1925 1700);
FORCEADD UNIVERSAL_POWER..1
(2075 2350);
FORCEPROP 3 LASTPIN (2075 2300) SIG_NAME P3V3_AUX\g
J 0
(2085 2310);
DISPLAY 0.659574 (2085 2310);
PAINT MONO (2085 2310);
DISPLAY INVISIBLE (2085 2310);
FORCEPROP 1 LAST HDL_POWER P3V3_AUX
J 1
(2075 2400);
DISPLAY 0.872340 (2075 2400);
PAINT GREEN (2075 2400);
FORCEPROP 2 LAST CDS_LIB pure_quanta_power
J 0
(2075 2350);
PAINT MONO (2075 2350);
DISPLAY INVISIBLE (2075 2350);
FORCEPROP 1 LAST PATH I54
J 0
(2125 2375);
DISPLAY 0.872340 (2125 2375);
PAINT AQUA (2125 2375);
DISPLAY INVISIBLE (2125 2375);
FORCEADD Q_RES..2
(2075 2100);
FORCEPROP 1 LAST LOCATION R3494
J 0
(2120 2225);
DISPLAY 0.787234 (2120 2225);
FORCEPROP 0 LAST $SEC 1
J 0
(2125 2275);
DISPLAY 0.680851 (2125 2275);
PAINT MONO (2125 2275);
DISPLAY INVISIBLE (2125 2275);
FORCEPROP 0 LAST CDS_SEC 1
J 0
(2125 2275);
DISPLAY 1.021277 (2125 2275);
DISPLAY INVISIBLE (2125 2275);
FORCEPROP 1 LASTPIN (2075 2200) $PN 1
J 0
(2080 2162);
DISPLAY 0.787234 (2080 2162);
PAINT MONO (2080 2162);
FORCEPROP 1 LASTPIN (2075 2000) $PN 2
J 0
(2080 2010);
DISPLAY 0.787234 (2080 2010);
PAINT MONO (2080 2010);
FORCEPROP 1 LAST PACK_TYPE 0402LF
J 0
(2115 1925);
DISPLAY 0.787234 (2115 1925);
FORCEPROP 1 LAST TOLERANCE 1%
J 0
(2120 2125);
DISPLAY 0.787234 (2120 2125);
FORCEPROP 1 LAST WATTAGE 1/16W
J 0
(2115 2075);
DISPLAY 0.787234 (2115 2075);
FORCEPROP 1 LAST MATERIAL CHIP
J 0
(2115 2025);
DISPLAY 0.787234 (2115 2025);
FORCEPROP 1 LAST VALUE 54.9K
J 0
(2120 2175);
DISPLAY 0.787234 (2120 2175);
FORCEPROP 2 LAST CDS_LIB pure_quanta
J 0
(2075 2100);
DISPLAY INVISIBLE (2075 2100);
FORCEPROP 1 LAST PATH I55
J 0
(2125 2275);
DISPLAY 0.978723 (2125 2275);
PAINT WHITE (2125 2275);
DISPLAY INVISIBLE (2125 2275);
FORCEPROP 1 LAST PART_NUMBER CS35492FB03
J 0
(2115 1975);
DISPLAY 0.787234 (2115 1975);
DISPLAY INVISIBLE (2115 1975);
FORCEADD UNIVERSAL_POWER..1
(-650 2325);
FORCEPROP 3 LASTPIN (-650 2275) SIG_NAME P3V3_AUX\g
J 0
(-640 2285);
DISPLAY 0.659574 (-640 2285);
PAINT MONO (-640 2285);
DISPLAY INVISIBLE (-640 2285);
FORCEPROP 1 LAST HDL_POWER P3V3_AUX
J 1
(-650 2375);
DISPLAY 0.872340 (-650 2375);
PAINT GREEN (-650 2375);
FORCEPROP 2 LAST CDS_LIB pure_quanta_power
J 0
(-650 2325);
PAINT MONO (-650 2325);
DISPLAY INVISIBLE (-650 2325);
FORCEPROP 1 LAST PATH I56
J 0
(-600 2350);
DISPLAY 0.872340 (-600 2350);
PAINT AQUA (-600 2350);
DISPLAY INVISIBLE (-600 2350);
FORCEADD Q_RES..2
(-650 2075);
FORCEPROP 1 LAST LOCATION R3490
J 0
(-605 2200);
DISPLAY 0.978723 (-605 2200);
FORCEPROP 0 LAST $SEC 1
J 0
(-600 2250);
DISPLAY 0.680851 (-600 2250);
PAINT MONO (-600 2250);
DISPLAY INVISIBLE (-600 2250);
FORCEPROP 0 LAST CDS_SEC 1
J 0
(-600 2250);
DISPLAY 1.021277 (-600 2250);
DISPLAY INVISIBLE (-600 2250);
FORCEPROP 1 LASTPIN (-650 2175) $PN 1
J 0
(-645 2137);
DISPLAY 0.787234 (-645 2137);
PAINT MONO (-645 2137);
FORCEPROP 1 LASTPIN (-650 1975) $PN 2
J 0
(-645 1985);
DISPLAY 0.787234 (-645 1985);
PAINT MONO (-645 1985);
FORCEPROP 1 LAST PACK_TYPE 0402LF
J 0
(-610 1950);
DISPLAY 0.638298 (-610 1950);
FORCEPROP 1 LAST WATTAGE 1/16W
J 0
(-610 2050);
DISPLAY 0.638298 (-610 2050);
FORCEPROP 1 LAST MATERIAL CHIP
J 0
(-610 2000);
DISPLAY 0.638298 (-610 2000);
FORCEPROP 1 LAST VALUE 1K
J 0
(-605 2150);
DISPLAY 0.638298 (-605 2150);
FORCEPROP 1 LAST TOLERANCE 1%
J 0
(-605 2100);
DISPLAY 0.638298 (-605 2100);
FORCEPROP 2 LAST CDS_LIB pure_quanta
J 0
(-650 2075);
DISPLAY INVISIBLE (-650 2075);
FORCEPROP 1 LAST PATH I57
J 0
(-600 2250);
DISPLAY 0.978723 (-600 2250);
PAINT WHITE (-600 2250);
DISPLAY INVISIBLE (-600 2250);
FORCEPROP 1 LAST PART_NUMBER CS21002FB06
J 0
(-610 1900);
DISPLAY 0.638298 (-610 1900);
DISPLAY INVISIBLE (-610 1900);
FORCEADD OFFPAGE..4
R 2
(-900 1800);
FORCEPROP 2 LAST $XR0 81 
J 0
(-1121 1800);
DISPLAY 0.638298 (-1121 1800);
PAINT MONO (-1121 1800);
FORCEPROP 2 LAST CDS_LIB standard
J 0
(-900 1800);
DISPLAY INVISIBLE (-900 1800);
FORCEPROP 1 LAST OFFPAGE TRUE
J 2
(-1225 1675);
DISPLAY 0.872340 (-1225 1675);
PAINT GREEN (-1225 1675);
DISPLAY INVISIBLE (-1225 1675);
FORCEPROP 1 LAST COMMENT_BODY TRUE
J 2
(-875 1700);
DISPLAY 0.872340 (-875 1700);
PAINT GREEN (-875 1700);
DISPLAY INVISIBLE (-875 1700);
FORCEPROP 2 LAST PATH I58
J 0
(-1150 1850);
DISPLAY 1.021277 (-1150 1850);
DISPLAY INVISIBLE (-1150 1850);
FORCEADD Q_RES..2
(2100 1500);
FORCEPROP 1 LAST LOCATION R3495
J 0
(2145 1625);
DISPLAY 0.978723 (2145 1625);
FORCEPROP 0 LAST $SEC 1
J 0
(2150 1675);
DISPLAY 0.680851 (2150 1675);
PAINT MONO (2150 1675);
DISPLAY INVISIBLE (2150 1675);
FORCEPROP 0 LAST CDS_SEC 1
J 0
(2150 1675);
DISPLAY 1.021277 (2150 1675);
DISPLAY INVISIBLE (2150 1675);
FORCEPROP 1 LASTPIN (2100 1600) $PN 1
J 0
(2105 1562);
DISPLAY 0.787234 (2105 1562);
PAINT MONO (2105 1562);
FORCEPROP 1 LASTPIN (2100 1400) $PN 2
J 0
(2105 1410);
DISPLAY 0.787234 (2105 1410);
PAINT MONO (2105 1410);
FORCEPROP 1 LAST VALUE 100K
J 0
(2145 1575);
DISPLAY 0.510638 (2145 1575);
FORCEPROP 1 LAST PACK_TYPE 0402LF
J 0
(2140 1325);
DISPLAY 0.510638 (2140 1325);
FORCEPROP 1 LAST WATTAGE 1/16W
J 0
(2140 1475);
DISPLAY 0.510638 (2140 1475);
FORCEPROP 1 LAST TOLERANCE 1%
J 0
(2145 1525);
DISPLAY 0.510638 (2145 1525);
FORCEPROP 1 LAST MATERIAL EMPTY
J 0
(2140 1425);
DISPLAY 0.510638 (2140 1425);
PAINT RED (2140 1425);
FORCEPROP 2 LAST CDS_LIB pure_quanta
J 0
(2100 1500);
DISPLAY INVISIBLE (2100 1500);
FORCEPROP 1 LAST PATH I62
J 0
(2150 1675);
DISPLAY 0.978723 (2150 1675);
PAINT WHITE (2150 1675);
DISPLAY INVISIBLE (2150 1675);
FORCEPROP 1 LAST PART_NUMBER CS41002FB09
J 0
(2140 1375);
DISPLAY 0.510638 (2140 1375);
DISPLAY INVISIBLE (2140 1375);
FORCEADD UNIVERSAL_GND..1
(2100 1300);
FORCEPROP 3 LASTPIN (2100 1350) SIG_NAME GND\g
J 0
(2110 1360);
DISPLAY 0.659574 (2110 1360);
PAINT MONO (2110 1360);
DISPLAY INVISIBLE (2110 1360);
FORCEPROP 2 LAST CDS_LIB pure_quanta_power
J 0
(2100 1300);
DISPLAY INVISIBLE (2100 1300);
FORCEPROP 1 LAST HDL_POWER GND
J 1
(2125 1225);
DISPLAY 0.872340 (2125 1225);
PAINT GREEN (2125 1225);
DISPLAY INVISIBLE (2125 1225);
FORCEPROP 1 LAST PATH I63
J 0
(2175 1300);
DISPLAY 0.872340 (2175 1300);
PAINT AQUA (2175 1300);
DISPLAY INVISIBLE (2175 1300);
FORCEADD UNIVERSAL_POWER..1
(1350 1375);
FORCEPROP 3 LASTPIN (1350 1325) SIG_NAME P3V3_AUX\g
J 0
(1360 1335);
DISPLAY 0.659574 (1360 1335);
PAINT MONO (1360 1335);
DISPLAY INVISIBLE (1360 1335);
FORCEPROP 1 LAST HDL_POWER P3V3_AUX
J 1
(1350 1425);
DISPLAY 0.872340 (1350 1425);
PAINT GREEN (1350 1425);
FORCEPROP 2 LAST CDS_LIB pure_quanta_power
J 0
(1350 1375);
PAINT MONO (1350 1375);
DISPLAY INVISIBLE (1350 1375);
FORCEPROP 1 LAST PATH I66
J 0
(1400 1400);
DISPLAY 0.872340 (1400 1400);
PAINT AQUA (1400 1400);
DISPLAY INVISIBLE (1400 1400);
FORCEADD Q_CAP..1
(1350 1050);
FORCEPROP 1 LAST LOCATION C1979
J 0
(1400 1150);
DISPLAY 0.787234 (1400 1150);
FORCEPROP 2 LAST $SEC 1
J 0
(1400 1250);
DISPLAY 0.680851 (1400 1250);
PAINT MONO (1400 1250);
DISPLAY INVISIBLE (1400 1250);
FORCEPROP 2 LAST CDS_SEC 1
J 0
(1400 1250);
DISPLAY 1.021277 (1400 1250);
DISPLAY INVISIBLE (1400 1250);
FORCEPROP 1 LASTPIN (1350 1150) $PN 1
J 0
(1360 1130);
DISPLAY 0.787234 (1360 1130);
FORCEPROP 1 LASTPIN (1350 950) $PN 2
J 0
(1360 930);
DISPLAY 0.787234 (1360 930);
FORCEPROP 1 LAST PACK_TYPE 0402
J 0
(1400 850);
DISPLAY 0.510638 (1400 850);
FORCEPROP 1 LAST MATERIAL X7R
J 0
(1400 950);
DISPLAY 0.510638 (1400 950);
FORCEPROP 1 LAST VOLTAGE 25V
J 0
(1400 1050);
DISPLAY 0.510638 (1400 1050);
FORCEPROP 1 LAST VALUE 0.1UF
J 0
(1400 1100);
DISPLAY 0.510638 (1400 1100);
FORCEPROP 1 LAST TOLERANCE 10%
J 0
(1400 1000);
DISPLAY 0.510638 (1400 1000);
FORCEPROP 2 LAST CDS_LIB pure_quanta
J 2
(1350 1050);
PAINT MONO (1350 1050);
DISPLAY INVISIBLE (1350 1050);
FORCEPROP 1 LAST PATH I67
J 0
(1400 1200);
DISPLAY 0.978723 (1400 1200);
PAINT WHITE (1400 1200);
DISPLAY INVISIBLE (1400 1200);
FORCEPROP 1 LAST PART_NUMBER CH4104K1B00
J 0
(1400 900);
DISPLAY 0.510638 (1400 900);
DISPLAY INVISIBLE (1400 900);
FORCEADD UNIVERSAL_GND..1
(1350 825);
FORCEPROP 3 LASTPIN (1350 875) SIG_NAME GND\g
J 0
(1360 885);
DISPLAY 0.659574 (1360 885);
PAINT MONO (1360 885);
DISPLAY INVISIBLE (1360 885);
FORCEPROP 2 LAST CDS_LIB pure_quanta_power
J 0
(1350 825);
PAINT MONO (1350 825);
DISPLAY INVISIBLE (1350 825);
FORCEPROP 1 LAST HDL_POWER GND
J 1
(1375 750);
DISPLAY 0.872340 (1375 750);
PAINT GREEN (1375 750);
DISPLAY INVISIBLE (1375 750);
FORCEPROP 1 LAST PATH I68
J 0
(1425 825);
DISPLAY 0.872340 (1425 825);
PAINT AQUA (1425 825);
DISPLAY INVISIBLE (1425 825);
FORCEADD UNIVERSAL_GND..1
(200 1100);
FORCEPROP 3 LASTPIN (200 1150) SIG_NAME GND\g
J 0
(210 1160);
DISPLAY 0.659574 (210 1160);
PAINT MONO (210 1160);
DISPLAY INVISIBLE (210 1160);
FORCEPROP 2 LAST CDS_LIB pure_quanta_power
J 0
(200 1100);
DISPLAY INVISIBLE (200 1100);
FORCEPROP 1 LAST HDL_POWER GND
J 1
(225 1025);
DISPLAY 0.872340 (225 1025);
PAINT GREEN (225 1025);
DISPLAY INVISIBLE (225 1025);
FORCEPROP 1 LAST PATH I69
J 0
(275 1100);
DISPLAY 0.872340 (275 1100);
PAINT AQUA (275 1100);
DISPLAY INVISIBLE (275 1100);
FORCEADD Q_RES..2
(-600 1600);
FORCEPROP 1 LAST LOCATION R3491
J 0
(-555 1725);
DISPLAY 0.978723 (-555 1725);
FORCEPROP 0 LAST $SEC 1
J 0
(-550 1775);
DISPLAY 0.680851 (-550 1775);
PAINT MONO (-550 1775);
DISPLAY INVISIBLE (-550 1775);
FORCEPROP 0 LAST CDS_SEC 1
J 0
(-550 1775);
DISPLAY 1.021277 (-550 1775);
DISPLAY INVISIBLE (-550 1775);
FORCEPROP 1 LASTPIN (-600 1700) $PN 1
J 0
(-595 1662);
DISPLAY 0.787234 (-595 1662);
PAINT MONO (-595 1662);
FORCEPROP 1 LASTPIN (-600 1500) $PN 2
J 0
(-595 1510);
DISPLAY 0.787234 (-595 1510);
PAINT MONO (-595 1510);
FORCEPROP 1 LAST VALUE 100K
J 0
(-555 1675);
DISPLAY 0.510638 (-555 1675);
FORCEPROP 1 LAST TOLERANCE 1%
J 0
(-555 1625);
DISPLAY 0.510638 (-555 1625);
FORCEPROP 1 LAST WATTAGE 1/16W
J 0
(-560 1575);
DISPLAY 0.510638 (-560 1575);
FORCEPROP 1 LAST PACK_TYPE 0402LF
J 0
(-560 1425);
DISPLAY 0.510638 (-560 1425);
FORCEPROP 1 LAST MATERIAL EMPTY
J 0
(-560 1525);
DISPLAY 0.510638 (-560 1525);
PAINT RED (-560 1525);
FORCEPROP 2 LAST CDS_LIB pure_quanta
J 0
(-600 1600);
DISPLAY INVISIBLE (-600 1600);
FORCEPROP 1 LAST PATH I70
J 0
(-550 1775);
DISPLAY 0.978723 (-550 1775);
PAINT WHITE (-550 1775);
DISPLAY INVISIBLE (-550 1775);
FORCEPROP 1 LAST PART_NUMBER CS41002FB09
J 0
(-560 1475);
DISPLAY 0.510638 (-560 1475);
DISPLAY INVISIBLE (-560 1475);
FORCEADD UNIVERSAL_GND..1
(-600 1400);
FORCEPROP 3 LASTPIN (-600 1450) SIG_NAME GND\g
J 0
(-590 1460);
DISPLAY 0.659574 (-590 1460);
PAINT MONO (-590 1460);
DISPLAY INVISIBLE (-590 1460);
FORCEPROP 2 LAST CDS_LIB pure_quanta_power
J 0
(-600 1400);
DISPLAY INVISIBLE (-600 1400);
FORCEPROP 1 LAST HDL_POWER GND
J 1
(-575 1325);
DISPLAY 0.872340 (-575 1325);
PAINT GREEN (-575 1325);
DISPLAY INVISIBLE (-575 1325);
FORCEPROP 1 LAST PATH I74
J 0
(-525 1400);
DISPLAY 0.872340 (-525 1400);
PAINT AQUA (-525 1400);
DISPLAY INVISIBLE (-525 1400);
FORCEADD Q_RES..2
(-650 4575);
FORCEPROP 1 LAST LOCATION R3459
J 0
(-605 4700);
DISPLAY 0.978723 (-605 4700);
FORCEPROP 0 LAST $SEC 1
J 0
(-600 4750);
DISPLAY 0.680851 (-600 4750);
PAINT MONO (-600 4750);
DISPLAY INVISIBLE (-600 4750);
FORCEPROP 0 LAST CDS_SEC 1
J 0
(-600 4750);
DISPLAY 0.680851 (-600 4750);
DISPLAY INVISIBLE (-600 4750);
FORCEPROP 1 LASTPIN (-650 4675) $PN 1
J 0
(-645 4637);
DISPLAY 0.787234 (-645 4637);
PAINT MONO (-645 4637);
FORCEPROP 1 LASTPIN (-650 4475) $PN 2
J 0
(-645 4485);
DISPLAY 0.787234 (-645 4485);
PAINT MONO (-645 4485);
FORCEPROP 1 LAST VALUE 1K
J 0
(-605 4650);
DISPLAY 0.638298 (-605 4650);
FORCEPROP 1 LAST TOLERANCE 1%
J 0
(-605 4600);
DISPLAY 0.638298 (-605 4600);
FORCEPROP 1 LAST PACK_TYPE 0402LF
J 0
(-610 4450);
DISPLAY 0.638298 (-610 4450);
FORCEPROP 1 LAST MATERIAL CHIP
J 0
(-610 4500);
DISPLAY 0.638298 (-610 4500);
FORCEPROP 1 LAST WATTAGE 1/16W
J 0
(-610 4550);
DISPLAY 0.638298 (-610 4550);
FORCEPROP 2 LAST CDS_LIB pure_quanta
J 0
(-650 4575);
DISPLAY INVISIBLE (-650 4575);
FORCEPROP 1 LAST PATH I75
J 0
(-600 4750);
DISPLAY 0.978723 (-600 4750);
PAINT WHITE (-600 4750);
DISPLAY INVISIBLE (-600 4750);
FORCEPROP 1 LAST PART_NUMBER CS21002FB06
J 0
(-610 4400);
DISPLAY 0.638298 (-610 4400);
DISPLAY INVISIBLE (-610 4400);
FORCEADD DNS..2
(1925 2775);
PAINT RED (1925 2775);
FORCEPROP 2 LAST CDS_LIB mstr_misc
J 0
(1925 2775);
DISPLAY INVISIBLE (1925 2775);
FORCEPROP 1 LAST COMMENT_BODY TRUE
J 0
(1925 2775);
DISPLAY INVISIBLE (1925 2775);
FORCEADD DNS..2
(1875 3975);
PAINT RED (1875 3975);
FORCEPROP 2 LAST CDS_LIB mstr_misc
J 0
(1875 3975);
DISPLAY INVISIBLE (1875 3975);
FORCEPROP 1 LAST COMMENT_BODY TRUE
J 0
(1875 3975);
DISPLAY INVISIBLE (1875 3975);
FORCEADD DNS..2
(-625 4075);
PAINT RED (-625 4075);
FORCEPROP 2 LAST CDS_LIB mstr_misc
J 0
(-625 4075);
DISPLAY INVISIBLE (-625 4075);
FORCEPROP 1 LAST COMMENT_BODY TRUE
J 0
(-625 4075);
DISPLAY INVISIBLE (-625 4075);
FORCEADD DNS..2
(-625 2925);
PAINT RED (-625 2925);
FORCEPROP 2 LAST CDS_LIB mstr_misc
J 0
(-625 2925);
DISPLAY INVISIBLE (-625 2925);
FORCEPROP 1 LAST COMMENT_BODY TRUE
J 0
(-625 2925);
DISPLAY INVISIBLE (-625 2925);
FORCEADD DNS..2
(-600 1575);
PAINT RED (-600 1575);
FORCEPROP 2 LAST CDS_LIB mstr_misc
J 0
(-600 1575);
DISPLAY INVISIBLE (-600 1575);
FORCEPROP 1 LAST COMMENT_BODY TRUE
J 0
(-600 1575);
DISPLAY INVISIBLE (-600 1575);
FORCEADD QUANTA_TITLE_BLOCK_C..1
(5475 -1300);
FORCEPROP 0 LAST CDS_CON_LAST_MODIFIED Thu Sep 14 16:12:24 2023
J 0
(3590 -1285);
DISPLAY INVISIBLE (3590 -1285);
FORCEPROP 1 LAST CUSTOM_TXT_CDS <CON_LAST_MODIFIED>
J 0
(3590 -1285);
DISPLAY 0.978723 (3590 -1285);
FORCEPROP 2 LAST CUSTOM_TXT_CDS <XR_PAGE_TITLE>
J 0
(-2415 3950);
DISPLAY 0.638298 (-2415 3950);
PAINT PINK (-2415 3950);
DISPLAY INVISIBLE (-2415 3950);
FORCEPROP 1 LAST CUSTOM_TXT_CDS <NAME_2>
J 0
(2300 -1250);
FORCEPROP 1 LAST CUSTOM_TXT_CDS <NAME_1>
J 0
(2300 -1125);
FORCEPROP 1 LAST CUSTOM_TXT_CDS <Q_NUMBER>
J 0
(4072 -1197);
DISPLAY 1.212766 (4072 -1197);
FORCEPROP 1 LAST CUSTOM_TXT_CDS <Q_PROJ>
J 0
(3093 -1198);
DISPLAY 1.212766 (3093 -1198);
FORCEPROP 1 LAST CUSTOM_TXT_CDS <Q_REV>
J 0
(5291 -1197);
DISPLAY 1.212766 (5291 -1197);
FORCEPROP 1 LAST CUSTOM_TXT_CDS <CON_PAGE_NUM> OF <CON_TOTAL_PAGES>
J 0
(5029 -1282);
DISPLAY 0.978723 (5029 -1282);
FORCEPROP 1 LAST Q_TITLE EXAMAX_ISO (6/7)
J 0
(-3825 -1250);
DISPLAY 2.446809 (-3825 -1250);
PAINT GREEN (-3825 -1250);
FORCEPROP 2 LAST PAGE_BORDER TRUE
J 0
(-2415 3950);
DISPLAY 0.638298 (-2415 3950);
PAINT PINK (-2415 3950);
DISPLAY INVISIBLE (-2415 3950);
FORCEPROP 1 LAST CDS_LMAN_SYM_OUTLINE -9475,6775,100,-125
J 0
(5475 -1300);
DISPLAY 0.468085 (5475 -1300);
PAINT GREEN (5475 -1300);
DISPLAY INVISIBLE (5475 -1300);
FORCEPROP 2 LAST CDS_LIB pure_quanta
J 0
(5475 -1300);
DISPLAY INVISIBLE (5475 -1300);
FORCEPROP 2 LAST CDS_XR_PAGE_TITLE CR-129 : @T6G_MB_LIB.T6G(SCH_1):PAGE129
J 0
(-2415 3950);
DISPLAY 0.638298 (-2415 3950);
PAINT PINK (-2415 3950);
DISPLAY INVISIBLE (-2415 3950);
FORCEPROP 1 LAST Q_DEPT BU9
J 1
(1712 -1251);
DISPLAY 1.957447 (1712 -1251);
PAINT GREEN (1712 -1251);
DISPLAY INVISIBLE (1712 -1251);
FORCEPROP 1 LAST COMMENT_BODY TRUE
J 0
(5487 -1313);
DISPLAY 0.978723 (5487 -1313);
PAINT GREEN (5487 -1313);
DISPLAY INVISIBLE (5487 -1313);
FORCEADD DNS..2
(2100 1475);
PAINT RED (2100 1475);
FORCEPROP 2 LAST CDS_LIB mstr_misc
J 0
(2100 1475);
DISPLAY INVISIBLE (2100 1475);
FORCEPROP 1 LAST COMMENT_BODY TRUE
J 0
(2100 1475);
DISPLAY INVISIBLE (2100 1475);
WIRE 16 -1 (1350 3450)(1350 3375);
WIRE 16 -1 (450 3750)(200 3750);
WIRE 16 -1 (200 3750)(200 3650);
WIRE 16 -1 (-650 4775)(-650 4675);
WIRE 16 -1 (-625 3950)(-625 4000);
WIRE 16 -1 (1850 4800)(1850 4700);
WIRE 16 -1 (1875 3900)(1875 3850);
WIRE 16 -1 (-650 3625)(-650 3525);
WIRE 16 -1 (-625 2800)(-625 2850);
WIRE 16 -1 (1900 3600)(1900 3500);
WIRE 16 -1 (1925 2700)(1925 2650);
WIRE 16 -1 (2075 2300)(2075 2200);
WIRE 16 -1 (-650 2275)(-650 2175);
WIRE 16 -1 (2100 1400)(2100 1350);
WIRE 16 -1 (1350 950)(1350 875);
WIRE 16 -1 (-600 1450)(-600 1500);
WIRE 16 -1 (450 1250)(200 1250);
WIRE 16 -1 (200 1250)(200 1200);
WIRE 16 -1 (450 1200)(200 1200);
WIRE 16 -1 (200 1200)(200 1150);
WIRE 16 -1 (-650 4475)(-650 4300);
WIRE 16 -1 (-625 4300)(-650 4300);
WIRE 16 -1 (-650 4300)(-850 4300);
WIRE 16 -1 (450 4300)(-625 4300);
FORCEPROP 2 LAST SIG_NAME GPU_NVS_PWR_BRAKE_N
J 0
(-585 4310);
DISPLAY 0.808511 (-585 4310);
WIRE 16 -1 (-625 4200)(-625 4300);
WIRE 16 -1 (450 4300)(450 3800);
WIRE 16 -1 (-650 1975)(-650 1800);
WIRE 16 -1 (-650 1800)(-600 1800);
WIRE 16 -1 (-650 1800)(-850 1800);
WIRE 16 -1 (450 1800)(-600 1800);
FORCEPROP 2 LAST SIG_NAME GPU_FPGA_EROT_RECOV_N
J 0
(-585 1810);
DISPLAY 0.808511 (-585 1810);
WIRE 16 -1 (-600 1700)(-600 1800);
WIRE 16 -1 (450 1800)(450 1300);
WIRE 16 -1 (450 3150)(-625 3150);
FORCEPROP 2 LAST SIG_NAME GPU_FPGA_EROT_RST_N
J 0
(-585 3160);
DISPLAY 0.808511 (-585 3160);
WIRE 16 -1 (450 3150)(450 3700);
WIRE 16 -1 (-625 3150)(-650 3150);
WIRE 16 -1 (-625 3050)(-625 3150);
WIRE 16 -1 (-650 3325)(-650 3150);
WIRE 16 -1 (-650 3150)(-850 3150);
WIRE 16 -1 (2100 1600)(2100 1800);
WIRE 16 -1 (2100 1800)(2225 1800);
WIRE 16 -1 (2075 1800)(2100 1800);
WIRE 16 -1 (2075 2000)(2075 1800);
WIRE 16 -1 (1100 1800)(2075 1800);
FORCEPROP 2 LAST SIG_NAME GPU_FPGA_EROT_RECOV_BUF_R_N
J 0
(1140 1810);
DISPLAY 0.638298 (1140 1810);
FORCEPROP 2 LASTPROP $XRERR UNIQUE?
J 0
(900 1810);
DISPLAY 0.638298 (900 1810);
PAINT MONO (900 1810);
DISPLAY INVISIBLE (900 1810);
WIRE 16 -1 (1100 1800)(1100 1300);
WIRE 16 -1 (1100 3700)(1100 3100);
WIRE 16 -1 (1900 3100)(1100 3100);
FORCEPROP 2 LAST SIG_NAME GPU_FPGA_EROT_RST_BUF_R_N
J 0
(1115 3110);
DISPLAY 0.638298 (1115 3110);
FORCEPROP 2 LASTPROP $XRERR UNIQUE?
J 0
(875 3110);
DISPLAY 0.638298 (875 3110);
PAINT MONO (875 3110);
DISPLAY INVISIBLE (875 3110);
WIRE 16 -1 (1900 3100)(1925 3100);
WIRE 16 -1 (1900 3300)(1900 3100);
WIRE 16 -1 (1925 3100)(2050 3100);
WIRE 16 -1 (1925 2900)(1925 3100);
WIRE 16 -1 (1800 1200)(1100 1200);
FORCEPROP 2 LAST SIG_NAME NC_U257_2Y
J 0
(1365 1210);
DISPLAY 0.808511 (1365 1210);
FORCEPROP 2 LASTPROP $XRERR UNIQUE?
J 0
(1830 1200);
DISPLAY 0.638298 (1830 1200);
PAINT MONO (1830 1200);
DISPLAY INVISIBLE (1830 1200);
WIRE 16 -1 (1875 4100)(1875 4300);
WIRE 16 -1 (1875 4300)(2000 4300);
WIRE 16 -1 (1850 4300)(1875 4300);
WIRE 16 -1 (1850 4500)(1850 4300);
WIRE 16 -1 (1100 4300)(1850 4300);
FORCEPROP 2 LAST SIG_NAME GPU_NVS_PWR_BRAKE_N_R
J 0
(1115 4310);
DISPLAY 0.638298 (1115 4310);
FORCEPROP 2 LASTPROP $XRERR UNIQUE?
J 0
(875 4310);
DISPLAY 0.638298 (875 4310);
PAINT MONO (875 4310);
DISPLAY INVISIBLE (875 4310);
WIRE 16 -1 (1100 4300)(1100 3800);
WIRE 16 -1 (1350 1325)(1350 1250);
WIRE 16 -1 (1350 1250)(1350 1150);
WIRE 16 -1 (1100 1250)(1350 1250);
WIRE 16 -1 (3550 1800)(2425 1800);
FORCEPROP 2 LAST SIG_NAME GPU_FPGA_EROT_RECOV_BUF_N
J 0
(2615 1810);
DISPLAY 0.808511 (2615 1810);
WIRE 16 -1 (3375 3100)(2250 3100);
FORCEPROP 2 LAST SIG_NAME GPU_FPGA_EROT_RST_BUF_N
J 0
(2440 3110);
DISPLAY 0.808511 (2440 3110);
WIRE 16 -1 (3325 4300)(2200 4300);
FORCEPROP 2 LAST SIG_NAME GPU_NVS_PWR_BRAKE_N_BUF
J 0
(2390 4310);
DISPLAY 0.808511 (2390 4310);
WIRE 16 -1 (1100 3750)(1350 3750);
WIRE 16 -1 (1350 3750)(1350 3650);
WIRE 16 -1 (1350 3825)(1350 3750);
DOT 1 (200 1200);
DOT 1 (-650 4300);
DOT 1 (1875 4300);
DOT 1 (1850 4300);
DOT 1 (1925 3100);
DOT 1 (1900 3100);
DOT 1 (1350 3750);
DOT 1 (2075 1800);
DOT 1 (2100 1800);
DOT 1 (1350 1250);
DOT 1 (-650 3150);
DOT 1 (-650 1800);
DOT 1 (-625 4300);
DOT 1 (-625 3150);
DOT 1 (-600 1800);
FORCENOTE
OPEN-DRAIN OUTPUT
(325 3000) 0;
DISPLAY LEFT (325 3000);
DISPLAY 1.021277 (325 3000);
PAINT WHITE (325 3000);
FORCENOTE
OPEN-DRAIN OUTPUT
(400 1000) 0;
DISPLAY LEFT (400 1000);
DISPLAY 1.021277 (400 1000);
PAINT WHITE (400 1000);
QUIT
